(kicad_pcb
	(version 20241229)
	(generator "pcbnew")
	(generator_version "9.0")
	(general
		(thickness 1.62)
		(legacy_teardrops no)
	)
	(paper "A3")
	(title_block
		(title "COM Express 7 Baseboard")
		(date "2025-02-04")
		(rev "1.1.2")
		(company "Antmicro Ltd")
		(comment 1 "www.antmicro.com")
		(comment 9 "footprints 330-334 of 802")
	)
	(layers
		(0 "F.Cu" signal)
		(4 "In1.Cu" signal)
		(6 "In2.Cu" signal)
		(8 "In3.Cu" signal)
		(10 "In4.Cu" signal)
		(12 "In5.Cu" signal)
		(14 "In6.Cu" signal)
		(2 "B.Cu" signal)
		(9 "F.Adhes" user "F.Adhesive")
		(11 "B.Adhes" user "B.Adhesive")
		(13 "F.Paste" user)
		(15 "B.Paste" user)
		(5 "F.SilkS" user "F.Silkscreen")
		(7 "B.SilkS" user "B.Silkscreen")
		(1 "F.Mask" user)
		(3 "B.Mask" user)
		(17 "Dwgs.User" user "User.Drawings")
		(19 "Cmts.User" user "User.Comments")
		(21 "Eco1.User" user "User.Eco1")
		(23 "Eco2.User" user "User.Eco2")
		(25 "Edge.Cuts" user)
		(27 "Margin" user)
		(31 "F.CrtYd" user "F.Courtyard")
		(29 "B.CrtYd" user "B.Courtyard")
		(35 "F.Fab" user)
		(33 "B.Fab" user)
	)
	(footprint "antmicro-footprints:C_0603_1608Metric"
		(layer "F.Cu")
		(at 226.7 159.9)
		(descr "Capacitor SMD 0603")
		(tags "capacitor 0603")
		(property "Reference" "C93"
			(at -3.49 -0.4 0)
			(layer "F.SilkS")
			(effects
				(font
					(size 0.7 0.7)
					(thickness 0.15)
				)
				(justify left top)
			)
		)
		(property "Value" "C_22u_16V_0603"
			(at 1.79743 -50.894712 0)
			(layer "F.Fab")
			(hide yes)
			(effects
				(font
					(size 0.7 0.7)
					(thickness 0.15)
				)
				(justify left top)
			)
		)
		(property "Datasheet" "https://product.samsungsem.com/mlcc/CL10A226MO7JZN.do"
			(at 0 0 0)
			(layer "F.Fab")
			(hide yes)
			(effects
				(font
					(size 1.27 1.27)
					(thickness 0.15)
				)
			)
		)
		(property "Author" "Antmicro"
			(at 359.1 320.92 0)
			(layer "F.Fab")
			(hide yes)
			(effects
				(font
					(size 1 1)
					(thickness 0.15)
				)
			)
		)
		(property "Dielectric" ""
			(at 359.1 320.92 0)
			(layer "F.Fab")
			(hide yes)
			(effects
				(font
					(size 1 1)
					(thickness 0.15)
				)
			)
		)
		(property "License" "Apache-2.0"
			(at 359.1 320.92 0)
			(layer "F.Fab")
			(hide yes)
			(effects
				(font
					(size 1 1)
					(thickness 0.15)
				)
			)
		)
		(property "MPN" "CL10A226MO7JZNC"
			(at 359.1 320.92 0)
			(layer "F.Fab")
			(hide yes)
			(effects
				(font
					(size 1 1)
					(thickness 0.15)
				)
			)
		)
		(property "Manufacturer" "Samsung Electro-Mechanics"
			(at 359.1 320.92 0)
			(layer "F.Fab")
			(hide yes)
			(effects
				(font
					(size 1 1)
					(thickness 0.15)
				)
			)
		)
		(property "Public" "False"
			(at 359.1 320.92 0)
			(layer "F.Fab")
			(hide yes)
			(effects
				(font
					(size 1 1)
					(thickness 0.15)
				)
			)
		)
		(property "Val" "22u"
			(at 359.1 320.92 0)
			(layer "F.Fab")
			(hide yes)
			(effects
				(font
					(size 1 1)
					(thickness 0.15)
				)
			)
		)
		(property "Voltage" "16V"
			(at 359.1 320.92 0)
			(layer "F.Fab")
			(hide yes)
			(effects
				(font
					(size 1 1)
					(thickness 0.15)
				)
			)
		)
		(sheetname "Com Express 7 MGMT")
		(sheetfile "com_express_7_mgmt.kicad_sch")
		(attr smd)
		(fp_line
			(start -0.15 -0.4)
			(end 0.15 -0.4)
			(stroke
				(width 0.15)
				(type solid)
			)
			(layer "F.SilkS")
		)
		(fp_line
			(start -0.15 0.4)
			(end 0.15 0.4)
			(stroke
				(width 0.15)
				(type solid)
			)
			(layer "F.SilkS")
		)
		(fp_rect
			(start -1.25 -0.65)
			(end 1.25 0.65)
			(stroke
				(width 0.05)
				(type solid)
			)
			(fill no)
			(layer "F.CrtYd")
		)
		(fp_rect
			(start -0.8 -0.4)
			(end 0.8 0.4)
			(stroke
				(width 0.15)
				(type solid)
			)
			(fill no)
			(layer "F.Fab")
		)
		(pad "1" smd roundrect
			(at -0.7 0)
			(size 0.8 1)
			(layers "F.Cu" "F.Mask" "F.Paste")
			(roundrect_rratio 0.2)
			(net 1 "GND")
			(pintype "passive")
			(teardrops
				(best_length_ratio 0.2)
				(max_length 1)
				(best_width_ratio 0.9)
				(max_width 2)
				(curved_edges yes)
				(filter_ratio 0.9)
				(enabled yes)
				(allow_two_segments yes)
				(prefer_zone_connections yes)
			)
		)
		(pad "2" smd roundrect
			(at 0.7 0)
			(size 0.8 1)
			(layers "F.Cu" "F.Mask" "F.Paste")
			(roundrect_rratio 0.2)
			(net 65 "+12V")
			(pintype "passive")
			(teardrops
				(best_length_ratio 0.2)
				(max_length 1)
				(best_width_ratio 0.9)
				(max_width 2)
				(curved_edges yes)
				(filter_ratio 0.9)
				(enabled yes)
				(allow_two_segments yes)
				(prefer_zone_connections yes)
			)
		)
	)
	(footprint "antmicro-footprints:C_Pol_EIA-B"
		(layer "F.Cu")
		(at 110.8 91.81 -90)
		(property "Reference" "C4"
			(at 2.35 -0.45 90)
			(layer "F.SilkS")
			(effects
				(font
					(size 0.7 0.7)
					(thickness 0.15)
				)
				(justify right bottom)
			)
		)
		(property "Value" "C_Pol_100u_10V_KEMET-T520-B"
			(at 0 2.85 90)
			(layer "F.Fab")
			(effects
				(font
					(size 0.7 0.7)
					(thickness 0.15)
				)
				(justify right bottom)
			)
		)
		(property "Datasheet" "https://www.kemet.com/en/us/capacitors/product/T520B107M010ATE070.html"
			(at 0 0 270)
			(layer "F.Fab")
			(hide yes)
			(effects
				(font
					(size 1.27 1.27)
					(thickness 0.15)
				)
			)
		)
		(property "Author" "Antmicro"
			(at 18.99 202.61 0)
			(layer "F.Fab")
			(hide yes)
			(effects
				(font
					(size 1 1)
					(thickness 0.15)
				)
			)
		)
		(property "Dielectric" "template_dielectric"
			(at 18.99 202.61 0)
			(layer "F.Fab")
			(hide yes)
			(effects
				(font
					(size 1 1)
					(thickness 0.15)
				)
			)
		)
		(property "License" "Apache-2.0"
			(at 18.99 202.61 0)
			(layer "F.Fab")
			(hide yes)
			(effects
				(font
					(size 1 1)
					(thickness 0.15)
				)
			)
		)
		(property "MPN" "T520B107M010ATE070"
			(at 18.99 202.61 0)
			(layer "F.Fab")
			(hide yes)
			(effects
				(font
					(size 1 1)
					(thickness 0.15)
				)
			)
		)
		(property "Manufacturer" "KEMET"
			(at 18.99 202.61 0)
			(layer "F.Fab")
			(hide yes)
			(effects
				(font
					(size 1 1)
					(thickness 0.15)
				)
			)
		)
		(property "Public" "False"
			(at 18.99 202.61 0)
			(layer "F.Fab")
			(hide yes)
			(effects
				(font
					(size 1 1)
					(thickness 0.15)
				)
			)
		)
		(property "Val" "100u"
			(at 18.99 202.61 0)
			(layer "F.Fab")
			(hide yes)
			(effects
				(font
					(size 1 1)
					(thickness 0.15)
				)
			)
		)
		(property "Voltage" "10V"
			(at 18.99 202.61 0)
			(layer "F.Fab")
			(hide yes)
			(effects
				(font
					(size 1 1)
					(thickness 0.15)
				)
			)
		)
		(sheetname "2xUSB3.0+RJ45")
		(sheetfile "usb3+rj45.kicad_sch")
		(attr smd)
		(fp_line
			(start 1.8 1.6)
			(end -1.8 1.6)
			(stroke
				(width 0.15)
				(type solid)
			)
			(layer "F.SilkS")
		)
		(fp_line
			(start -1.8 1.3)
			(end -1.8 1.6)
			(stroke
				(width 0.15)
				(type solid)
			)
			(layer "F.SilkS")
		)
		(fp_line
			(start 1.8 1.3)
			(end 1.8 1.6)
			(stroke
				(width 0.15)
				(type solid)
			)
			(layer "F.SilkS")
		)
		(fp_line
			(start -1.8 -1.3)
			(end -1.8 -1.6)
			(stroke
				(width 0.15)
				(type solid)
			)
			(layer "F.SilkS")
		)
		(fp_line
			(start 1.8 -1.3)
			(end 1.8 -1.6)
			(stroke
				(width 0.15)
				(type solid)
			)
			(layer "F.SilkS")
		)
		(fp_line
			(start -2.325 -1.475)
			(end -2.325 -1.878)
			(stroke
				(width 0.15)
				(type solid)
			)
			(layer "F.SilkS")
		)
		(fp_line
			(start -1.8 -1.6)
			(end 1.8 -1.6)
			(stroke
				(width 0.15)
				(type solid)
			)
			(layer "F.SilkS")
		)
		(fp_line
			(start -2.521 -1.676)
			(end -2.123 -1.676)
			(stroke
				(width 0.15)
				(type solid)
			)
			(layer "F.SilkS")
		)
		(fp_line
			(start 1.96 1.75)
			(end -1.97 1.75)
			(stroke
				(width 0.05)
				(type solid)
			)
			(layer "F.CrtYd")
		)
		(fp_line
			(start -1.97 1.35)
			(end -1.97 1.75)
			(stroke
				(width 0.05)
				(type solid)
			)
			(layer "F.CrtYd")
		)
		(fp_line
			(start -1.97 1.35)
			(end -2.41 1.35)
			(stroke
				(width 0.05)
				(type solid)
			)
			(layer "F.CrtYd")
		)
		(fp_line
			(start 1.96 1.35)
			(end 1.96 1.75)
			(stroke
				(width 0.05)
				(type solid)
			)
			(layer "F.CrtYd")
		)
		(fp_line
			(start 2.4 1.35)
			(end 1.96 1.35)
			(stroke
				(width 0.05)
				(type solid)
			)
			(layer "F.CrtYd")
		)
		(fp_line
			(start -2.411 -1.35)
			(end -2.41 1.35)
			(stroke
				(width 0.05)
				(type solid)
			)
			(layer "F.CrtYd")
		)
		(fp_line
			(start -1.97 -1.35)
			(end -2.41 -1.35)
			(stroke
				(width 0.05)
				(type solid)
			)
			(layer "F.CrtYd")
		)
		(fp_line
			(start 2.399 -1.35)
			(end 2.4 1.35)
			(stroke
				(width 0.05)
				(type solid)
			)
			(layer "F.CrtYd")
		)
		(fp_line
			(start 2.399 -1.35)
			(end 1.959 -1.35)
			(stroke
				(width 0.05)
				(type solid)
			)
			(layer "F.CrtYd")
		)
		(fp_line
			(start -1.97 -1.75)
			(end -1.97 -1.35)
			(stroke
				(width 0.05)
				(type solid)
			)
			(layer "F.CrtYd")
		)
		(fp_line
			(start 1.959 -1.75)
			(end 1.959 -1.35)
			(stroke
				(width 0.05)
				(type solid)
			)
			(layer "F.CrtYd")
		)
		(fp_line
			(start 1.959 -1.75)
			(end -1.97 -1.75)
			(stroke
				(width 0.05)
				(type solid)
			)
			(layer "F.CrtYd")
		)
		(fp_line
			(start -1.7 1.324)
			(end -1.551 1.475)
			(stroke
				(width 0.15)
				(type solid)
			)
			(layer "F.Fab")
		)
		(fp_rect
			(start -1.72 -1.5)
			(end 1.719 1.499)
			(stroke
				(width 0.15)
				(type solid)
			)
			(fill no)
			(layer "F.Fab")
		)
		(pad "1" smd roundrect
			(at -1.551 0 270)
			(size 1.2 2.2)
			(layers "F.Cu" "F.Mask" "F.Paste")
			(roundrect_rratio 0.1)
			(net 43 "/2xUSB3.0+RJ45/P2_VBUS")
			(pintype "passive")
			(teardrops
				(best_length_ratio 0.2)
				(max_length 1)
				(best_width_ratio 0.9)
				(max_width 2)
				(curved_edges yes)
				(filter_ratio 0.9)
				(enabled yes)
				(allow_two_segments yes)
				(prefer_zone_connections yes)
			)
		)
		(pad "2" smd roundrect
			(at 1.55 0 270)
			(size 1.2 2.2)
			(layers "F.Cu" "F.Mask" "F.Paste")
			(roundrect_rratio 0.1)
			(net 1 "GND")
			(pintype "passive")
			(teardrops
				(best_length_ratio 0.2)
				(max_length 1)
				(best_width_ratio 0.9)
				(max_width 2)
				(curved_edges yes)
				(filter_ratio 0.9)
				(enabled yes)
				(allow_two_segments yes)
				(prefer_zone_connections yes)
			)
		)
	)
	(footprint "antmicro-footprints:TP_SMD_0.75mm"
		(layer "F.Cu")
		(at 136.89 129.56)
		(property "Reference" "TP87"
			(at 0.46 -1.25 90)
			(layer "F.SilkS")
			(effects
				(font
					(size 0.7 0.7)
					(thickness 0.15)
				)
				(justify left bottom)
			)
		)
		(property "Value" "TP_0.75mm_SMD"
			(at 0 1.2 0)
			(layer "F.Fab")
			(effects
				(font
					(size 0.7 0.7)
					(thickness 0.15)
				)
				(justify left bottom)
			)
		)
		(property "Author" "Antmicro"
			(at 0 0 0)
			(layer "F.Fab")
			(hide yes)
			(effects
				(font
					(size 1 1)
					(thickness 0.15)
				)
			)
		)
		(property "License" "Apache-2.0"
			(at 0 0 0)
			(layer "F.Fab")
			(hide yes)
			(effects
				(font
					(size 1 1)
					(thickness 0.15)
				)
			)
		)
		(property "MPN" ""
			(at 0 0 0)
			(layer "F.Fab")
			(hide yes)
			(effects
				(font
					(size 1 1)
					(thickness 0.15)
				)
			)
		)
		(property "Manufacturer" ""
			(at 0 0 0)
			(layer "F.Fab")
			(hide yes)
			(effects
				(font
					(size 1 1)
					(thickness 0.15)
				)
			)
		)
		(property "Public" "False"
			(at 0 0 0)
			(layer "F.Fab")
			(hide yes)
			(effects
				(font
					(size 1 1)
					(thickness 0.15)
				)
			)
		)
		(sheetname "KR to SFI #2")
		(sheetfile "kr_sfi.kicad_sch")
		(attr exclude_from_pos_files exclude_from_bom)
		(fp_circle
			(center 0 0)
			(end 0.475 0)
			(stroke
				(width 0.05)
				(type default)
			)
			(fill no)
			(layer "F.CrtYd")
		)
		(pad "1" smd circle
			(at 0 0)
			(size 0.75 0.75)
			(layers "F.Cu" "F.Mask")
			(net 750 "Net-(U45C-CLKOUTA+)")
			(pinfunction "1")
			(pintype "passive")
			(teardrops
				(best_length_ratio 0.4)
				(max_length 1)
				(best_width_ratio 0.9)
				(max_width 2)
				(curved_edges yes)
				(filter_ratio 0.9)
				(enabled yes)
				(allow_two_segments yes)
				(prefer_zone_connections yes)
			)
		)
	)
	(footprint "antmicro-footprints:R_0402_1005Metric"
		(layer "F.Cu")
		(at 130.119 117.85 180)
		(descr "Resistor SMD 0402")
		(tags "resistor SMD 0402")
		(property "Reference" "R20"
			(at 0.781 0.42 0)
			(layer "F.SilkS")
			(effects
				(font
					(size 0.7 0.7)
					(thickness 0.15)
				)
				(justify right top)
			)
		)
		(property "Value" "R_0R_0402"
			(at -1.011843 1.772046 0)
			(layer "F.Fab")
			(effects
				(font
					(size 0.7 0.7)
					(thickness 0.15)
				)
				(justify right top)
			)
		)
		(property "Datasheet" "https://industrial.panasonic.com/cdbs/www-data/pdf/RDA0000/AOA0000C301.pdf"
			(at 0 0 0)
			(layer "F.Fab")
			(hide yes)
			(effects
				(font
					(size 1.27 1.27)
					(thickness 0.15)
				)
			)
		)
		(property "Author" "Antmicro"
			(at 357.371 -61.189 90)
			(layer "F.Fab")
			(hide yes)
			(effects
				(font
					(size 1 1)
					(thickness 0.15)
				)
			)
		)
		(property "Current" "1A"
			(at 357.371 -61.189 90)
			(layer "F.Fab")
			(hide yes)
			(effects
				(font
					(size 1 1)
					(thickness 0.15)
				)
			)
		)
		(property "License" "Apache-2.0"
			(at 357.371 -61.189 90)
			(layer "F.Fab")
			(hide yes)
			(effects
				(font
					(size 1 1)
					(thickness 0.15)
				)
			)
		)
		(property "MPN" "ERJ2GE0R00X"
			(at 357.371 -61.189 90)
			(layer "F.Fab")
			(hide yes)
			(effects
				(font
					(size 1 1)
					(thickness 0.15)
				)
			)
		)
		(property "Manufacturer" "Panasonic"
			(at 357.371 -61.189 90)
			(layer "F.Fab")
			(hide yes)
			(effects
				(font
					(size 1 1)
					(thickness 0.15)
				)
			)
		)
		(property "Public" "False"
			(at 357.371 -61.189 90)
			(layer "F.Fab")
			(hide yes)
			(effects
				(font
					(size 1 1)
					(thickness 0.15)
				)
			)
		)
		(property "Tolerance" ""
			(at 357.371 -61.189 90)
			(layer "F.Fab")
			(hide yes)
			(effects
				(font
					(size 1 1)
					(thickness 0.15)
				)
			)
		)
		(property "Val" "0R"
			(at 357.371 -61.189 90)
			(layer "F.Fab")
			(hide yes)
			(effects
				(font
					(size 1 1)
					(thickness 0.15)
				)
			)
		)
		(sheetname "2xUSB3.0+RJ45")
		(sheetfile "usb3+rj45.kicad_sch")
		(attr smd)
		(fp_rect
			(start -0.925 -0.47)
			(end 0.925 0.47)
			(stroke
				(width 0.05)
				(type default)
			)
			(fill no)
			(layer "F.CrtYd")
		)
		(fp_rect
			(start -0.5 -0.25)
			(end 0.5 0.25)
			(stroke
				(width 0.15)
				(type solid)
			)
			(fill no)
			(layer "F.Fab")
		)
		(pad "1" smd roundrect
			(at -0.48 0 180)
			(size 0.59 0.64)
			(layers "F.Cu" "F.Mask" "F.Paste")
			(roundrect_rratio 0.25)
			(net 313 "/2xUSB3.0+RJ45/USB_1.D+")
			(pintype "passive")
			(teardrops
				(best_length_ratio 0.2)
				(max_length 1)
				(best_width_ratio 0.9)
				(max_width 2)
				(curved_edges yes)
				(filter_ratio 0.9)
				(enabled yes)
				(allow_two_segments yes)
				(prefer_zone_connections yes)
			)
		)
		(pad "2" smd roundrect
			(at 0.48 0 180)
			(size 0.59 0.64)
			(layers "F.Cu" "F.Mask" "F.Paste")
			(roundrect_rratio 0.25)
			(net 124 "/2xUSB3.0+RJ45/P1_D+")
			(pintype "passive")
			(teardrops
				(best_length_ratio 0.2)
				(max_length 1)
				(best_width_ratio 0.9)
				(max_width 2)
				(curved_edges yes)
				(filter_ratio 0.9)
				(enabled yes)
				(allow_two_segments yes)
				(prefer_zone_connections yes)
			)
		)
	)
	(footprint "antmicro-footprints:Mech_SolidRun_LX2160A-CEX7"
		(layer "F.Cu")
		(at 157.93 171.81 90)
		(property "Reference" "A3"
			(at 0 -0.5 90)
			(unlocked yes)
			(layer "F.SilkS")
			(hide yes)
			(effects
				(font
					(size 0.7 0.7)
					(thickness 0.15)
				)
				(justify left bottom)
			)
		)
		(property "Value" "Mech_SolidRun_LX2160A-CEX7"
			(at 0 1 90)
			(unlocked yes)
			(layer "F.Fab")
			(effects
				(font
					(size 0.7 0.7)
					(thickness 0.15)
				)
				(justify left bottom)
			)
		)
		(property "Datasheet" "https://www.solid-run.com/embedded-networking/nxp-lx2160a-family/cex7-lx2160/#documentation"
			(at 0 0 90)
			(layer "F.Fab")
			(hide yes)
			(effects
				(font
					(size 1.27 1.27)
					(thickness 0.15)
				)
			)
		)
		(property "Author" "Antmicro"
			(at 329.74 13.88 0)
			(layer "F.Fab")
			(hide yes)
			(effects
				(font
					(size 1 1)
					(thickness 0.15)
				)
			)
		)
		(property "Displayed name" "LX2160A-CEX7"
			(at 329.74 13.88 0)
			(layer "F.Fab")
			(hide yes)
			(effects
				(font
					(size 1 1)
					(thickness 0.15)
				)
			)
		)
		(property "License" "Apache-2.0"
			(at 329.74 13.88 0)
			(layer "F.Fab")
			(hide yes)
			(effects
				(font
					(size 1 1)
					(thickness 0.15)
				)
			)
		)
		(property "MPN" "SRX2160S01D00GE064V21C0"
			(at 329.74 13.88 0)
			(layer "F.Fab")
			(hide yes)
			(effects
				(font
					(size 1 1)
					(thickness 0.15)
				)
			)
		)
		(property "Manufacturer" "SolidRun"
			(at 329.74 13.88 0)
			(layer "F.Fab")
			(hide yes)
			(effects
				(font
					(size 1 1)
					(thickness 0.15)
				)
			)
		)
		(sheetname "Com Express 7 Interfaces")
		(sheetfile "com_express_7_interfaces.kicad_sch")
		(attr through_hole exclude_from_pos_files exclude_from_bom allow_missing_courtyard
			dnp
		)
		(fp_rect
			(start 0 0)
			(end 95 125)
			(stroke
				(width 0.15)
				(type solid)
			)
			(fill no)
			(layer "F.Fab")
		)
		(fp_circle
			(center 91 4)
			(end 94 4)
			(stroke
				(width 0.1)
				(type default)
			)
			(fill no)
			(layer "F.Fab")
		)
		(fp_circle
			(center 4 4)
			(end 7 4)
			(stroke
				(width 0.1)
				(type default)
			)
			(fill no)
			(layer "F.Fab")
		)
		(fp_circle
			(center 18 16.5)
			(end 19 16.5)
			(stroke
				(width 0.1)
				(type default)
			)
			(fill no)
			(layer "F.Fab")
		)
		(fp_circle
			(center 6 16.5)
			(end 7 16.5)
			(stroke
				(width 0.1)
				(type default)
			)
			(fill no)
			(layer "F.Fab")
		)
		(fp_circle
			(center 4 80)
			(end 7 80)
			(stroke
				(width 0.1)
				(type default)
			)
			(fill no)
			(layer "F.Fab")
		)
		(fp_circle
			(center 91 121)
			(end 94 121)
			(stroke
				(width 0.1)
				(type default)
			)
			(fill no)
			(layer "F.Fab")
		)
		(fp_circle
			(center 4 121)
			(end 7 121)
			(stroke
				(width 0.1)
				(type default)
			)
			(fill no)
			(layer "F.Fab")
		)
	)
)
